(kicad_pcb
	(version 20260206)
	(generator "pcbnew")
	(generator_version "10.0")
	(general
		(thickness 1.6)
		(legacy_teardrops no)
	)
	(paper "A4")
	(title_block
		(title "Wiwynn_Tioga_Pass_MB.brd")
		(comment 1 "Tioga Pass / footprints 175-181 of 4770")
	)
	(layers
		(0 "F.Cu" signal "TOP")
		(4 "In1.Cu" signal "L2GND")
		(6 "In2.Cu" signal "L3")
		(8 "In3.Cu" signal "L4GND")
		(10 "In4.Cu" signal "L5")
		(12 "In5.Cu" signal "L6GND")
		(14 "In6.Cu" signal "L7VCC")
		(16 "In7.Cu" signal "L8VCC")
		(18 "In8.Cu" signal "L9GND")
		(20 "In9.Cu" signal "L10")
		(22 "In10.Cu" signal "L11GND")
		(24 "In11.Cu" signal "L12")
		(26 "In12.Cu" signal "L13GND")
		(2 "B.Cu" signal "BOTTOM")
		(9 "F.Adhes" user "F.Adhesive")
		(11 "B.Adhes" user "B.Adhesive")
		(13 "F.Paste" user "Package Geometry/Pastemask Top")
		(15 "B.Paste" user "Package Geometry/Pastemask Bottom")
		(5 "F.SilkS" user "Ref Des/Silkscreen Top")
		(7 "B.SilkS" user "Ref Des/Silkscreen Bottom")
		(1 "F.Mask" user "Board Geometry/Soldermask Top")
		(3 "B.Mask" user "Board Geometry/Soldermask Bottom")
		(17 "Dwgs.User" user "User.Drawings")
		(19 "Cmts.User" user "User.Comments")
		(21 "Eco1.User" user "User.Eco1")
		(23 "Eco2.User" user "User.Eco2")
		(25 "Edge.Cuts" user "Board Geometry/Outline")
		(27 "Margin" user)
		(31 "F.CrtYd" user "Package Geometry/Place Bound Top")
		(29 "B.CrtYd" user "Package Geometry/Place Bound Bottom")
		(35 "F.Fab" user "Ref Des/Assembly Top")
		(33 "B.Fab" user "Ref Des/Assembly Bottom")
	)
	(footprint ""
		(layer "F.Cu")
		(at 193.7385 -83.212432 90)
		(property "Reference" "C4D9"
			(at 0 0 90)
			(layer "F.SilkS")
			(hide yes)
			(effects
				(font
					(size 1.27 1.27)
				)
			)
		)
		(property "Value" ""
			(at 0 0 90)
			(layer "F.Fab")
			(effects
				(font
					(size 1.27 1.27)
				)
			)
		)
		(duplicate_pad_numbers_are_jumpers no)
		(fp_rect
			(start -0.3048 0.9906)
			(end 0.3048 -0.1016)
			(stroke
				(width 0)
				(type default)
			)
			(fill no)
			(layer "F.CrtYd")
		)
		(fp_line
			(start 0.3048 -0.1016)
			(end -0.3048 -0.1016)
			(stroke
				(width 0.1)
				(type default)
			)
			(layer "F.Fab")
		)
		(fp_line
			(start -0.3048 -0.1016)
			(end -0.3048 0.9906)
			(stroke
				(width 0.1)
				(type default)
			)
			(layer "F.Fab")
		)
		(fp_line
			(start 0.3048 0.9906)
			(end 0.3048 -0.1016)
			(stroke
				(width 0.1)
				(type default)
			)
			(layer "F.Fab")
		)
		(fp_line
			(start -0.3048 0.9906)
			(end 0.3048 0.9906)
			(stroke
				(width 0.1)
				(type default)
			)
			(layer "F.Fab")
		)
		(pad "1" smd rect
			(at 0 0 90)
			(size 0.508 0.508)
			(layers "F.Cu" "F.Mask" "F.Paste")
			(net "VR_PVCCIN_CPU0_PH4_BOOT")
		)
		(pad "2" smd rect
			(at 0 0.889 90)
			(size 0.508 0.508)
			(layers "F.Cu" "F.Mask" "F.Paste")
			(net "VR_PVCCIN_CPU0_PH4_PHASE")
		)
		(zone
			(layer "F.Cu")
			(hatch none 0.5)
			(connect_pads
				(clearance 0)
			)
			(min_thickness 0.25)
			(keepout
				(tracks not_allowed)
				(vias allowed)
				(pads allowed)
				(copperpour not_allowed)
				(footprints allowed)
			)
			(placement
				(enabled no)
				(sheetname "")
			)
			(fill
				(thermal_gap 0.5)
				(thermal_bridge_width 0.5)
				(island_removal_mode 0)
			)
			(polygon
				(pts
					(xy 194.3735 -82.958432) (xy 194.3735 -83.466432) (xy 193.9925 -83.466432) (xy 193.9925 -82.958432)
				)
			)
		)
		(zone
			(layer "F.Cu")
			(hatch none 0.5)
			(connect_pads
				(clearance 0)
			)
			(min_thickness 0.25)
			(keepout
				(tracks allowed)
				(vias not_allowed)
				(pads allowed)
				(copperpour not_allowed)
				(footprints allowed)
			)
			(placement
				(enabled no)
				(sheetname "")
			)
			(fill
				(thermal_gap 0.5)
				(thermal_bridge_width 0.5)
				(island_removal_mode 0)
			)
			(polygon
				(pts
					(xy 194.3735 -82.958432) (xy 194.3735 -83.466432) (xy 193.9925 -83.466432) (xy 193.9925 -82.958432)
				)
			)
		)
	)
	(footprint ""
		(layer "F.Cu")
		(at 325.0057 -29.25318)
		(property "Reference" "C6F3"
			(at 0 0 0)
			(layer "F.SilkS")
			(hide yes)
			(effects
				(font
					(size 1.27 1.27)
				)
			)
		)
		(property "Value" ""
			(at 0 0 0)
			(layer "F.Fab")
			(effects
				(font
					(size 1.27 1.27)
				)
			)
		)
		(duplicate_pad_numbers_are_jumpers no)
		(fp_poly
			(pts
				(xy 0.3048 -0.1016) (xy 0.3048 0.9906) (xy -0.3048 0.9906) (xy -0.3048 -0.1016)
			)
			(stroke
				(width 0)
				(type default)
			)
			(fill no)
			(layer "F.CrtYd")
		)
		(fp_line
			(start -0.3048 -0.1016)
			(end -0.3048 0.9906)
			(stroke
				(width 0.1)
				(type default)
			)
			(layer "F.Fab")
		)
		(fp_line
			(start -0.3048 0.9906)
			(end 0.3048 0.9906)
			(stroke
				(width 0.1)
				(type default)
			)
			(layer "F.Fab")
		)
		(fp_line
			(start 0.3048 -0.1016)
			(end -0.3048 -0.1016)
			(stroke
				(width 0.1)
				(type default)
			)
			(layer "F.Fab")
		)
		(fp_line
			(start 0.3048 0.9906)
			(end 0.3048 -0.1016)
			(stroke
				(width 0.1)
				(type default)
			)
			(layer "F.Fab")
		)
		(pad "1" smd rect
			(at 0 0)
			(size 0.508 0.508)
			(layers "F.Cu" "F.Mask" "F.Paste")
			(net "PVPP_ABC")
		)
		(pad "2" smd rect
			(at 0 0.889)
			(size 0.508 0.508)
			(layers "F.Cu" "F.Mask" "F.Paste")
			(net "GND")
		)
		(zone
			(layer "F.Cu")
			(hatch none 0.5)
			(connect_pads
				(clearance 0)
			)
			(min_thickness 0.25)
			(keepout
				(tracks allowed)
				(vias not_allowed)
				(pads allowed)
				(copperpour not_allowed)
				(footprints allowed)
			)
			(placement
				(enabled no)
				(sheetname "")
			)
			(fill
				(thermal_gap 0.5)
				(thermal_bridge_width 0.5)
				(island_removal_mode 0)
			)
			(polygon
				(pts
					(xy 324.7517 -28.99918) (xy 325.2597 -28.99918) (xy 325.2597 -28.61818) (xy 324.7517 -28.61818)
				)
			)
		)
		(zone
			(layer "F.Cu")
			(hatch none 0.5)
			(connect_pads
				(clearance 0)
			)
			(min_thickness 0.25)
			(keepout
				(tracks not_allowed)
				(vias allowed)
				(pads allowed)
				(copperpour not_allowed)
				(footprints allowed)
			)
			(placement
				(enabled no)
				(sheetname "")
			)
			(fill
				(thermal_gap 0.5)
				(thermal_bridge_width 0.5)
				(island_removal_mode 0)
			)
			(polygon
				(pts
					(xy 324.7517 -28.61818) (xy 325.2597 -28.61818) (xy 325.2597 -28.99918) (xy 324.7517 -28.99918)
				)
			)
		)
	)
	(footprint ""
		(layer "F.Cu")
		(at 153.6446 -126.7714 -90)
		(property "Reference" "C3B3"
			(at 3.10007 5.3086 0)
			(unlocked yes)
			(layer "F.SilkS")
			(effects
				(font
					(size 0.7874 0.5842)
					(thickness 0.1524)
				)
				(justify left)
			)
		)
		(property "Value" ""
			(at 0 0 270)
			(layer "F.Fab")
			(effects
				(font
					(size 1.27 1.27)
				)
			)
		)
		(duplicate_pad_numbers_are_jumpers no)
		(fp_line
			(start -2.2987 7.3533)
			(end -1.7272 7.3533)
			(stroke
				(width 0.1524)
				(type default)
			)
			(layer "F.SilkS")
		)
		(fp_line
			(start 1.7272 7.3533)
			(end 2.2987 7.3533)
			(stroke
				(width 0.1524)
				(type default)
			)
			(layer "F.SilkS")
		)
		(fp_line
			(start 2.2987 7.3533)
			(end 2.2987 -0.2413)
			(stroke
				(width 0.1524)
				(type default)
			)
			(layer "F.SilkS")
		)
		(fp_line
			(start -2.032 1.524)
			(end -1.7272 1.524)
			(stroke
				(width 0.1524)
				(type default)
			)
			(layer "F.SilkS")
		)
		(fp_line
			(start 2.032 1.524)
			(end 1.7272 1.524)
			(stroke
				(width 0.1524)
				(type default)
			)
			(layer "F.SilkS")
		)
		(fp_line
			(start -2.2987 -0.2413)
			(end -2.2987 7.3533)
			(stroke
				(width 0.1524)
				(type default)
			)
			(layer "F.SilkS")
		)
		(fp_line
			(start -2.032 -0.2413)
			(end -2.2987 -0.2413)
			(stroke
				(width 0.1524)
				(type default)
			)
			(layer "F.SilkS")
		)
		(fp_line
			(start 2.2987 -0.2413)
			(end 2.032 -0.2413)
			(stroke
				(width 0.1524)
				(type default)
			)
			(layer "F.SilkS")
		)
		(fp_line
			(start -2.032 -1.524)
			(end -2.032 1.524)
			(stroke
				(width 0.1524)
				(type default)
			)
			(layer "F.SilkS")
		)
		(fp_line
			(start -1.7272 -1.524)
			(end -2.032 -1.524)
			(stroke
				(width 0.1524)
				(type default)
			)
			(layer "F.SilkS")
		)
		(fp_line
			(start 1.7272 -1.524)
			(end 2.032 -1.524)
			(stroke
				(width 0.1524)
				(type default)
			)
			(layer "F.SilkS")
		)
		(fp_line
			(start 2.032 -1.524)
			(end 2.032 1.524)
			(stroke
				(width 0.1524)
				(type default)
			)
			(layer "F.SilkS")
		)
		(fp_poly
			(pts
				(xy -2.2987 -0.2413) (xy 2.2987 -0.2413) (xy 2.2987 7.3533) (xy -2.2987 7.3533)
			)
			(stroke
				(width 0)
				(type default)
			)
			(fill no)
			(layer "F.CrtYd")
		)
		(fp_line
			(start -2.2987 7.3533)
			(end -2.2987 -0.2413)
			(stroke
				(width 0.1)
				(type default)
			)
			(layer "F.Fab")
		)
		(fp_line
			(start 2.2987 7.3533)
			(end -2.2987 7.3533)
			(stroke
				(width 0.1)
				(type default)
			)
			(layer "F.Fab")
		)
		(fp_line
			(start -2.2987 -0.2413)
			(end 2.2987 -0.2413)
			(stroke
				(width 0.1)
				(type default)
			)
			(layer "F.Fab")
		)
		(fp_line
			(start 2.2987 -0.2413)
			(end 2.2987 7.3533)
			(stroke
				(width 0.1)
				(type default)
			)
			(layer "F.Fab")
		)
		(pad "1" smd rect
			(at 0 0 270)
			(size 2.54 3.048)
			(layers "F.Cu" "F.Mask" "F.Paste")
			(net "PVPP_KLM")
		)
		(pad "2" smd rect
			(at 0 7.112 270)
			(size 2.54 3.048)
			(layers "F.Cu" "F.Mask" "F.Paste")
			(net "GND")
		)
	)
	(footprint ""
		(layer "F.Cu")
		(at 273.37258 -84.39912 180)
		(property "Reference" "R3P29"
			(at 0 0 180)
			(layer "F.SilkS")
			(hide yes)
			(effects
				(font
					(size 1.27 1.27)
				)
			)
		)
		(property "Value" ""
			(at 0 0 180)
			(layer "F.Fab")
			(effects
				(font
					(size 1.27 1.27)
				)
			)
		)
		(duplicate_pad_numbers_are_jumpers no)
		(fp_poly
			(pts
				(xy -0.2794 -0.1016) (xy 0.2794 -0.1016) (xy 0.2794 0.9906) (xy -0.2794 0.9906)
			)
			(stroke
				(width 0)
				(type default)
			)
			(fill no)
			(layer "F.CrtYd")
		)
		(fp_line
			(start 0.2794 0.9906)
			(end 0.2794 -0.1016)
			(stroke
				(width 0.1)
				(type default)
			)
			(layer "F.Fab")
		)
		(fp_line
			(start 0.2794 -0.1016)
			(end -0.2794 -0.1016)
			(stroke
				(width 0.1)
				(type default)
			)
			(layer "F.Fab")
		)
		(fp_line
			(start -0.2794 0.9906)
			(end 0.2794 0.9906)
			(stroke
				(width 0.1)
				(type default)
			)
			(layer "F.Fab")
		)
		(fp_line
			(start -0.2794 -0.1016)
			(end -0.2794 0.9906)
			(stroke
				(width 0.1)
				(type default)
			)
			(layer "F.Fab")
		)
		(pad "1" smd rect
			(at 0 0 180)
			(size 0.508 0.508)
			(layers "F.Cu" "F.Mask" "F.Paste")
			(net "PVDDQ_DEF")
		)
		(pad "2" smd rect
			(at 0 0.889 180)
			(size 0.508 0.508)
			(layers "F.Cu" "F.Mask" "F.Paste")
			(net "PWRGD_CPU0_DRAMPWROK_DEF_G")
		)
		(zone
			(layer "F.Cu")
			(hatch none 0.5)
			(connect_pads
				(clearance 0)
			)
			(min_thickness 0.25)
			(keepout
				(tracks not_allowed)
				(vias allowed)
				(pads allowed)
				(copperpour not_allowed)
				(footprints allowed)
			)
			(placement
				(enabled no)
				(sheetname "")
			)
			(fill
				(thermal_gap 0.5)
				(thermal_bridge_width 0.5)
				(island_removal_mode 0)
			)
			(polygon
				(pts
					(xy 273.62658 -85.03412) (xy 273.11858 -85.03412) (xy 273.11858 -84.65312) (xy 273.62658 -84.65312)
				)
			)
		)
		(zone
			(layer "F.Cu")
			(hatch none 0.5)
			(connect_pads
				(clearance 0)
			)
			(min_thickness 0.25)
			(keepout
				(tracks allowed)
				(vias not_allowed)
				(pads allowed)
				(copperpour not_allowed)
				(footprints allowed)
			)
			(placement
				(enabled no)
				(sheetname "")
			)
			(fill
				(thermal_gap 0.5)
				(thermal_bridge_width 0.5)
				(island_removal_mode 0)
			)
			(polygon
				(pts
					(xy 273.62658 -84.65312) (xy 273.11858 -84.65312) (xy 273.11858 -85.03412) (xy 273.62658 -85.03412)
				)
			)
		)
	)
	(footprint ""
		(layer "F.Cu")
		(at 367.077244 -10.916158)
		(property "Reference" "C7G9"
			(at 0 0 0)
			(layer "F.SilkS")
			(hide yes)
			(effects
				(font
					(size 1.27 1.27)
				)
			)
		)
		(property "Value" ""
			(at 0 0 0)
			(layer "F.Fab")
			(effects
				(font
					(size 1.27 1.27)
				)
			)
		)
		(duplicate_pad_numbers_are_jumpers no)
		(fp_rect
			(start -0.3048 0.9906)
			(end 0.3048 -0.1016)
			(stroke
				(width 0)
				(type default)
			)
			(fill no)
			(layer "F.CrtYd")
		)
		(fp_line
			(start -0.3048 -0.1016)
			(end -0.3048 0.9906)
			(stroke
				(width 0.1)
				(type default)
			)
			(layer "F.Fab")
		)
		(fp_line
			(start -0.3048 0.9906)
			(end 0.3048 0.9906)
			(stroke
				(width 0.1)
				(type default)
			)
			(layer "F.Fab")
		)
		(fp_line
			(start 0.3048 -0.1016)
			(end -0.3048 -0.1016)
			(stroke
				(width 0.1)
				(type default)
			)
			(layer "F.Fab")
		)
		(fp_line
			(start 0.3048 0.9906)
			(end 0.3048 -0.1016)
			(stroke
				(width 0.1)
				(type default)
			)
			(layer "F.Fab")
		)
		(pad "1" smd rect
			(at 0 0)
			(size 0.508 0.508)
			(layers "F.Cu" "F.Mask" "F.Paste")
			(net "P3E_CPU0_PE2_SS_TXP<13>")
		)
		(pad "2" smd rect
			(at 0 0.889)
			(size 0.508 0.508)
			(layers "F.Cu" "F.Mask" "F.Paste")
			(net "P3E_CPU0_PE2_SS_C_TXP<13>")
		)
		(zone
			(layer "F.Cu")
			(hatch none 0.5)
			(connect_pads
				(clearance 0)
			)
			(min_thickness 0.25)
			(keepout
				(tracks allowed)
				(vias not_allowed)
				(pads allowed)
				(copperpour not_allowed)
				(footprints allowed)
			)
			(placement
				(enabled no)
				(sheetname "")
			)
			(fill
				(thermal_gap 0.5)
				(thermal_bridge_width 0.5)
				(island_removal_mode 0)
			)
			(polygon
				(pts
					(xy 366.823244 -10.281158) (xy 367.331244 -10.281158) (xy 367.331244 -10.662158) (xy 366.823244 -10.662158)
				)
			)
		)
		(zone
			(layer "F.Cu")
			(hatch none 0.5)
			(connect_pads
				(clearance 0)
			)
			(min_thickness 0.25)
			(keepout
				(tracks not_allowed)
				(vias allowed)
				(pads allowed)
				(copperpour not_allowed)
				(footprints allowed)
			)
			(placement
				(enabled no)
				(sheetname "")
			)
			(fill
				(thermal_gap 0.5)
				(thermal_bridge_width 0.5)
				(island_removal_mode 0)
			)
			(polygon
				(pts
					(xy 366.823244 -10.281158) (xy 367.331244 -10.281158) (xy 367.331244 -10.662158) (xy 366.823244 -10.662158)
				)
			)
		)
	)
	(footprint ""
		(layer "F.Cu")
		(at 398.325848 -150.071074)
		(property "Reference" "C8A9"
			(at 0 0 0)
			(layer "F.SilkS")
			(hide yes)
			(effects
				(font
					(size 1.27 1.27)
				)
			)
		)
		(property "Value" ""
			(at 0 0 0)
			(layer "F.Fab")
			(effects
				(font
					(size 1.27 1.27)
				)
			)
		)
		(duplicate_pad_numbers_are_jumpers no)
		(fp_poly
			(pts
				(xy 0.3048 -0.1016) (xy 0.3048 0.9906) (xy -0.3048 0.9906) (xy -0.3048 -0.1016)
			)
			(stroke
				(width 0)
				(type default)
			)
			(fill no)
			(layer "F.CrtYd")
		)
		(fp_line
			(start -0.3048 -0.1016)
			(end -0.3048 0.9906)
			(stroke
				(width 0.1)
				(type default)
			)
			(layer "F.Fab")
		)
		(fp_line
			(start -0.3048 0.9906)
			(end 0.3048 0.9906)
			(stroke
				(width 0.1)
				(type default)
			)
			(layer "F.Fab")
		)
		(fp_line
			(start 0.3048 -0.1016)
			(end -0.3048 -0.1016)
			(stroke
				(width 0.1)
				(type default)
			)
			(layer "F.Fab")
		)
		(fp_line
			(start 0.3048 0.9906)
			(end 0.3048 -0.1016)
			(stroke
				(width 0.1)
				(type default)
			)
			(layer "F.Fab")
		)
		(pad "1" smd rect
			(at 0 0)
			(size 0.508 0.508)
			(layers "F.Cu" "F.Mask" "F.Paste")
			(net "PWRGD_PVNN_PCH_R")
		)
		(pad "2" smd rect
			(at 0 0.889)
			(size 0.508 0.508)
			(layers "F.Cu" "F.Mask" "F.Paste")
			(net "GND")
		)
		(zone
			(layer "F.Cu")
			(hatch none 0.5)
			(connect_pads
				(clearance 0)
			)
			(min_thickness 0.25)
			(keepout
				(tracks allowed)
				(vias not_allowed)
				(pads allowed)
				(copperpour not_allowed)
				(footprints allowed)
			)
			(placement
				(enabled no)
				(sheetname "")
			)
			(fill
				(thermal_gap 0.5)
				(thermal_bridge_width 0.5)
				(island_removal_mode 0)
			)
			(polygon
				(pts
					(xy 398.071848 -149.817074) (xy 398.579848 -149.817074) (xy 398.579848 -149.436074) (xy 398.071848 -149.436074)
				)
			)
		)
		(zone
			(layer "F.Cu")
			(hatch none 0.5)
			(connect_pads
				(clearance 0)
			)
			(min_thickness 0.25)
			(keepout
				(tracks not_allowed)
				(vias allowed)
				(pads allowed)
				(copperpour not_allowed)
				(footprints allowed)
			)
			(placement
				(enabled no)
				(sheetname "")
			)
			(fill
				(thermal_gap 0.5)
				(thermal_bridge_width 0.5)
				(island_removal_mode 0)
			)
			(polygon
				(pts
					(xy 398.071848 -149.436074) (xy 398.579848 -149.436074) (xy 398.579848 -149.817074) (xy 398.071848 -149.817074)
				)
			)
		)
	)
	(footprint ""
		(layer "F.Cu")
		(at 275.7932 -79.6036 180)
		(property "Reference" "C5D23"
			(at 0 0 180)
			(layer "F.SilkS")
			(hide yes)
			(effects
				(font
					(size 1.27 1.27)
				)
			)
		)
		(property "Value" ""
			(at 0 0 180)
			(layer "F.Fab")
			(effects
				(font
					(size 1.27 1.27)
				)
			)
		)
		(duplicate_pad_numbers_are_jumpers no)
		(fp_poly
			(pts
				(xy -0.4953 -0.2032) (xy 0.4953 -0.2032) (xy 0.4953 1.6002) (xy -0.4953 1.6002)
			)
			(stroke
				(width 0)
				(type default)
			)
			(fill no)
			(layer "F.CrtYd")
		)
		(fp_line
			(start 0.4953 1.6002)
			(end -0.4953 1.6002)
			(stroke
				(width 0.1)
				(type default)
			)
			(layer "F.Fab")
		)
		(fp_line
			(start 0.4953 -0.2032)
			(end 0.4953 1.6002)
			(stroke
				(width 0.1)
				(type default)
			)
			(layer "F.Fab")
		)
		(fp_line
			(start -0.4953 1.6002)
			(end -0.4953 -0.2032)
			(stroke
				(width 0.1)
				(type default)
			)
			(layer "F.Fab")
		)
		(fp_line
			(start -0.4953 -0.2032)
			(end 0.4953 -0.2032)
			(stroke
				(width 0.1)
				(type default)
			)
			(layer "F.Fab")
		)
		(pad "1" smd rect
			(at 0 0 180)
			(size 0.762 0.889)
			(layers "F.Cu" "F.Mask" "F.Paste")
			(net "PVCCMCP_CPU0")
		)
		(pad "2" smd rect
			(at 0 1.397 180)
			(size 0.762 0.889)
			(layers "F.Cu" "F.Mask" "F.Paste")
			(net "GND")
		)
		(zone
			(layer "F.Cu")
			(hatch none 0.5)
			(connect_pads
				(clearance 0)
			)
			(min_thickness 0.25)
			(keepout
				(tracks not_allowed)
				(vias allowed)
				(pads allowed)
				(copperpour not_allowed)
				(footprints allowed)
			)
			(placement
				(enabled no)
				(sheetname "")
			)
			(fill
				(thermal_gap 0.5)
				(thermal_bridge_width 0.5)
				(island_removal_mode 0)
			)
			(polygon
				(pts
					(xy 276.1742 -80.0481) (xy 275.4122 -80.0481) (xy 275.4122 -80.5561) (xy 276.1742 -80.5561)
				)
			)
		)
	)
)
